# T6G (Grand Teton) — schematic netlist excerpt (pin names and nets, part order shuffled) for the footprints in the layout excerpt that follows; sources: Cadence DE-HDL packaged netlist, KiCad conversion of 04192023_DAF0TMB3IC0_F0TG_MB_C_brd_V02_OCP.brd

C2194  Q_CAP  0.1UF 25V 10% X7R  pkg 0402  page 257 : A = P12V_E1S_0_ISENSE_TIC ; B = GND
R2489  Q_RES  33.2 1% CHIP  pkg 0402LF  page 133 : A = IRQ_LVC3_WAKE_BUF_N ; B = IRQ_OCP_SFF_WAKE_BUF_N

(kicad_pcb
	(version 20260206)
	(generator "pcbnew")
	(generator_version "10.0")
	(general
		(thickness 1.6)
		(legacy_teardrops no)
	)
	(paper "A4")
	(title_block
		(title "04192023_DAF0TMB3IC0_F0TG_MB_C_brd_V02_OCP.brd")
		(comment 1 "Grand Teton / footprints 884-885 of 8354")
	)
	(layers
		(0 "F.Cu" signal "TOP")
		(4 "In1.Cu" signal "GND")
		(6 "In2.Cu" signal "IN1")
		(8 "In3.Cu" signal "GND1")
		(10 "In4.Cu" signal "IN2")
		(12 "In5.Cu" signal "GND2")
		(14 "In6.Cu" signal "IN3")
		(16 "In7.Cu" signal "GND3")
		(18 "In8.Cu" signal "VCC")
		(20 "In9.Cu" signal "VCC1")
		(22 "In10.Cu" signal "GND4")
		(24 "In11.Cu" signal "IN4")
		(26 "In12.Cu" signal "GND5")
		(28 "In13.Cu" signal "IN5")
		(30 "In14.Cu" signal "GND6")
		(32 "In15.Cu" signal "IN6")
		(34 "In16.Cu" signal "GND7")
		(2 "B.Cu" signal "BOTTOM")
		(9 "F.Adhes" user "F.Adhesive")
		(11 "B.Adhes" user "B.Adhesive")
		(13 "F.Paste" user "Package Geometry/Pastemask Top")
		(15 "B.Paste" user "Package Geometry/Pastemask Bottom")
		(5 "F.SilkS" user "Ref Des/Silkscreen Top")
		(7 "B.SilkS" user "Ref Des/Silkscreen Bottom")
		(1 "F.Mask" user "Board Geometry/Soldermask Top")
		(3 "B.Mask" user "Board Geometry/Soldermask Bottom")
		(17 "Dwgs.User" user "User.Drawings")
		(19 "Cmts.User" user "User.Comments")
		(21 "Eco1.User" user "User.Eco1")
		(23 "Eco2.User" user "User.Eco2")
		(25 "Edge.Cuts" user "Board Geometry/Outline")
		(27 "Margin" user)
		(31 "F.CrtYd" user "Package Geometry/Place Bound Top")
		(29 "B.CrtYd" user "Package Geometry/Place Bound Bottom")
		(35 "F.Fab" user "Ref Des/Assembly Top")
		(33 "B.Fab" user "Ref Des/Assembly Bottom")
	)
	(footprint ""
		(layer "F.Cu")
		(at 319.940178 -39.55542)
		(property "Reference" "C2194"
			(at 0 0 0)
			(layer "F.SilkS")
			(hide yes)
			(effects
				(font
					(size 1.27 1.27)
				)
			)
		)
		(property "Value" ""
			(at 0 0 0)
			(layer "F.Fab")
			(effects
				(font
					(size 1.27 1.27)
				)
			)
		)
		(duplicate_pad_numbers_are_jumpers no)
		(fp_line
			(start -0.7874 -0.4064)
			(end 0.7874 -0.4064)
			(stroke
				(width 0.1524)
				(type default)
			)
			(layer "F.SilkS")
		)
		(fp_line
			(start -0.7874 0.4064)
			(end -0.7874 -0.4064)
			(stroke
				(width 0.1524)
				(type default)
			)
			(layer "F.SilkS")
		)
		(fp_line
			(start 0.7874 -0.4064)
			(end 0.7874 0.4064)
			(stroke
				(width 0.1524)
				(type default)
			)
			(layer "F.SilkS")
		)
		(fp_line
			(start 0.7874 0.4064)
			(end -0.7874 0.4064)
			(stroke
				(width 0.1524)
				(type default)
			)
			(layer "F.SilkS")
		)
		(fp_line
			(start -0.67945 -0.305054)
			(end -0.12065 -0.305054)
			(stroke
				(width 0.1)
				(type default)
			)
			(layer "F.Fab")
		)
		(fp_line
			(start -0.67945 0.3048)
			(end -0.67945 -0.305054)
			(stroke
				(width 0.1)
				(type default)
			)
			(layer "F.Fab")
		)
		(fp_line
			(start -0.12065 -0.305054)
			(end -0.12065 -0.2794)
			(stroke
				(width 0.1)
				(type default)
			)
			(layer "F.Fab")
		)
		(fp_line
			(start -0.12065 -0.2794)
			(end 0.12065 -0.2794)
			(stroke
				(width 0.1)
				(type default)
			)
			(layer "F.Fab")
		)
		(fp_line
			(start -0.12065 0.2794)
			(end -0.12065 0.3048)
			(stroke
				(width 0.1)
				(type default)
			)
			(layer "F.Fab")
		)
		(fp_line
			(start -0.12065 0.3048)
			(end -0.67945 0.3048)
			(stroke
				(width 0.1)
				(type default)
			)
			(layer "F.Fab")
		)
		(fp_line
			(start 0.120396 0.2794)
			(end -0.12065 0.2794)
			(stroke
				(width 0.1)
				(type default)
			)
			(layer "F.Fab")
		)
		(fp_line
			(start 0.120396 0.3048)
			(end 0.120396 0.2794)
			(stroke
				(width 0.1)
				(type default)
			)
			(layer "F.Fab")
		)
		(fp_line
			(start 0.12065 -0.3048)
			(end 0.67945 -0.3048)
			(stroke
				(width 0.1)
				(type default)
			)
			(layer "F.Fab")
		)
		(fp_line
			(start 0.12065 -0.2794)
			(end 0.12065 -0.3048)
			(stroke
				(width 0.1)
				(type default)
			)
			(layer "F.Fab")
		)
		(fp_line
			(start 0.67945 -0.3048)
			(end 0.67945 0.3048)
			(stroke
				(width 0.1)
				(type default)
			)
			(layer "F.Fab")
		)
		(fp_line
			(start 0.67945 0.3048)
			(end 0.120396 0.3048)
			(stroke
				(width 0.1)
				(type default)
			)
			(layer "F.Fab")
		)
		(pad "1" smd circle
			(at -0.40005 0)
			(size 0 0)
			(layers "F.Cu" "F.Mask" "F.Paste")
			(net "P12V_E1S_0_ISENSE_TIC")
		)
		(pad "2" smd circle
			(at 0.40005 0)
			(size 0 0)
			(layers "F.Cu" "F.Mask" "F.Paste")
			(net "GND")
		)
	)
	(footprint ""
		(layer "F.Cu")
		(at 164.142674 -38.493954 90)
		(property "Reference" "R2489"
			(at 0 0 90)
			(layer "F.SilkS")
			(hide yes)
			(effects
				(font
					(size 1.27 1.27)
				)
			)
		)
		(property "Value" ""
			(at 0 0 90)
			(layer "F.Fab")
			(effects
				(font
					(size 1.27 1.27)
				)
			)
		)
		(duplicate_pad_numbers_are_jumpers no)
		(fp_line
			(start 0.7874 -0.4064)
			(end 0.7874 0.4064)
			(stroke
				(width 0.1524)
				(type default)
			)
			(layer "F.SilkS")
		)
		(fp_line
			(start -0.7874 -0.4064)
			(end 0.7874 -0.4064)
			(stroke
				(width 0.1524)
				(type default)
			)
			(layer "F.SilkS")
		)
		(fp_line
			(start 0.7874 0.4064)
			(end -0.7874 0.4064)
			(stroke
				(width 0.1524)
				(type default)
			)
			(layer "F.SilkS")
		)
		(fp_line
			(start -0.7874 0.4064)
			(end -0.7874 -0.4064)
			(stroke
				(width 0.1524)
				(type default)
			)
			(layer "F.SilkS")
		)
		(fp_line
			(start -0.12065 -0.305054)
			(end -0.12065 -0.2794)
			(stroke
				(width 0.1)
				(type default)
			)
			(layer "F.Fab")
		)
		(fp_line
			(start -0.67945 -0.305054)
			(end -0.12065 -0.305054)
			(stroke
				(width 0.1)
				(type default)
			)
			(layer "F.Fab")
		)
		(fp_line
			(start 0.67945 -0.3048)
			(end 0.67945 0.3048)
			(stroke
				(width 0.1)
				(type default)
			)
			(layer "F.Fab")
		)
		(fp_line
			(start 0.12065 -0.3048)
			(end 0.67945 -0.3048)
			(stroke
				(width 0.1)
				(type default)
			)
			(layer "F.Fab")
		)
		(fp_line
			(start 0.12065 -0.2794)
			(end 0.12065 -0.3048)
			(stroke
				(width 0.1)
				(type default)
			)
			(layer "F.Fab")
		)
		(fp_line
			(start -0.12065 -0.2794)
			(end 0.12065 -0.2794)
			(stroke
				(width 0.1)
				(type default)
			)
			(layer "F.Fab")
		)
		(fp_line
			(start 0.120396 0.2794)
			(end -0.12065 0.2794)
			(stroke
				(width 0.1)
				(type default)
			)
			(layer "F.Fab")
		)
		(fp_line
			(start -0.12065 0.2794)
			(end -0.12065 0.3048)
			(stroke
				(width 0.1)
				(type default)
			)
			(layer "F.Fab")
		)
		(fp_line
			(start 0.67945 0.3048)
			(end 0.120396 0.3048)
			(stroke
				(width 0.1)
				(type default)
			)
			(layer "F.Fab")
		)
		(fp_line
			(start 0.120396 0.3048)
			(end 0.120396 0.2794)
			(stroke
				(width 0.1)
				(type default)
			)
			(layer "F.Fab")
		)
		(fp_line
			(start -0.12065 0.3048)
			(end -0.67945 0.3048)
			(stroke
				(width 0.1)
				(type default)
			)
			(layer "F.Fab")
		)
		(fp_line
			(start -0.67945 0.3048)
			(end -0.67945 -0.305054)
			(stroke
				(width 0.1)
				(type default)
			)
			(layer "F.Fab")
		)
		(pad "1" smd circle
			(at -0.40005 0 90)
			(size 0 0)
			(layers "F.Cu" "F.Mask" "F.Paste")
			(net "IRQ_LVC3_WAKE_BUF_N")
		)
		(pad "2" smd circle
			(at 0.40005 0 90)
			(size 0 0)
			(layers "F.Cu" "F.Mask" "F.Paste")
			(net "IRQ_OCP_SFF_WAKE_BUF_N")
		)
	)
)
